(kicad_pcb
	(version 20260206)
	(generator "pcbnew")
	(generator_version "10.0")
	(general
		(thickness 1.6)
		(legacy_teardrops no)
	)
	(paper "A4")
	(title_block
		(title "Bryce Canyon_F.DPB_16315-1-OCP.brd")
		(comment 1 "Bryce Canyon / footprints 1691-1698 of 2223")
	)
	(layers
		(0 "F.Cu" signal "TOP")
		(4 "In1.Cu" signal "L2GND")
		(6 "In2.Cu" signal "L3")
		(8 "In3.Cu" signal "L4GND")
		(10 "In4.Cu" signal "L5")
		(12 "In5.Cu" signal "L6VCC")
		(14 "In6.Cu" signal "L7VCC")
		(16 "In7.Cu" signal "L8")
		(18 "In8.Cu" signal "L9GND")
		(20 "In9.Cu" signal "L10")
		(22 "In10.Cu" signal "L11GND")
		(2 "B.Cu" signal "BOTTOM")
		(9 "F.Adhes" user "F.Adhesive")
		(11 "B.Adhes" user "B.Adhesive")
		(13 "F.Paste" user "Package Geometry/Pastemask Top")
		(15 "B.Paste" user "Package Geometry/Pastemask Bottom")
		(5 "F.SilkS" user "Ref Des/Silkscreen Top")
		(7 "B.SilkS" user "Ref Des/Silkscreen Bottom")
		(1 "F.Mask" user "Board Geometry/Soldermask Top")
		(3 "B.Mask" user "Board Geometry/Soldermask Bottom")
		(17 "Dwgs.User" user "User.Drawings")
		(19 "Cmts.User" user "User.Comments")
		(21 "Eco1.User" user "User.Eco1")
		(23 "Eco2.User" user "User.Eco2")
		(25 "Edge.Cuts" user "Board Geometry/Outline")
		(27 "Margin" user)
		(31 "F.CrtYd" user "Package Geometry/Place Bound Top")
		(29 "B.CrtYd" user "Package Geometry/Place Bound Bottom")
		(35 "F.Fab" user "Ref Des/Assembly Top")
		(33 "B.Fab" user "Ref Des/Assembly Bottom")
	)
	(footprint ""
		(layer "F.Cu")
		(at 303.816766 -262.567674 -90)
		(property "Reference" "R447"
			(at 0 0 270)
			(layer "F.SilkS")
			(hide yes)
			(effects
				(font
					(size 1.27 1.27)
				)
			)
		)
		(property "Value" "1KR2F-3-GP"
			(at 0.064008 -3.993896 270)
			(unlocked yes)
			(layer "F.Fab")
			(hide yes)
			(effects
				(font
					(size 1.016 1.016)
					(thickness 0.1524)
				)
			)
		)
		(property "Device Type" "R402H16"
			(at 0.064008 -5.517896 270)
			(unlocked yes)
			(layer "F.Fab")
			(hide yes)
			(effects
				(font
					(size 1.016 1.016)
					(thickness 0.1524)
				)
			)
		)
		(duplicate_pad_numbers_are_jumpers no)
		(fp_line
			(start -0.508 -0.9398)
			(end -0.508 0.9398)
			(stroke
				(width 0.1524)
				(type default)
			)
			(layer "F.SilkS")
		)
		(fp_line
			(start 0.508 -0.9398)
			(end -0.508 -0.9398)
			(stroke
				(width 0.1524)
				(type default)
			)
			(layer "F.SilkS")
		)
		(fp_rect
			(start -0.508 0.9398)
			(end 0.508 -0.9398)
			(stroke
				(width 0)
				(type default)
			)
			(fill no)
			(layer "F.CrtYd")
		)
		(fp_rect
			(start -0.508 0.9398)
			(end 0.508 -0.9398)
			(stroke
				(width 0)
				(type default)
			)
			(fill no)
			(layer "F.Fab")
		)
		(pad "1" smd custom
			(at 0 -0.4445 270)
			(size 0.1397 0.1397)
			(layers "F.Cu" "F.Mask" "F.Paste")
			(net "P3V3_STBY_A")
			(options
				(clearance outline)
				(anchor circle)
			)
			(primitives
				(gr_poly
					(pts
						(arc
							(start -0.1778 -0.2794)
							(mid -0.249642 -0.249642)
							(end -0.2794 -0.1778)
						)
						(arc
							(start -0.2794 0.1778)
							(mid -0.249642 0.249642)
							(end -0.1778 0.2794)
						)
						(arc
							(start 0.1778 0.2794)
							(mid 0.249642 0.249642)
							(end 0.2794 0.1778)
						)
						(arc
							(start 0.2794 -0.1778)
							(mid 0.249642 -0.249642)
							(end 0.1778 -0.2794)
						)
					)
					(width 0)
					(fill yes)
				)
			)
		)
		(pad "2" smd custom
			(at 0 0.4445 270)
			(size 0.1397 0.1397)
			(layers "F.Cu" "F.Mask" "F.Paste")
			(net "I2C_BMC_B_EXP_A_SDA")
			(options
				(clearance outline)
				(anchor circle)
			)
			(primitives
				(gr_poly
					(pts
						(arc
							(start -0.1778 -0.2794)
							(mid -0.249642 -0.249642)
							(end -0.2794 -0.1778)
						)
						(arc
							(start -0.2794 0.1778)
							(mid -0.249642 0.249642)
							(end -0.1778 0.2794)
						)
						(arc
							(start 0.1778 0.2794)
							(mid 0.249642 0.249642)
							(end 0.2794 0.1778)
						)
						(arc
							(start 0.2794 -0.1778)
							(mid 0.249642 -0.249642)
							(end 0.1778 -0.2794)
						)
					)
					(width 0)
					(fill yes)
				)
			)
		)
	)
	(footprint ""
		(layer "F.Cu")
		(at 363.020102 -73.954894 180)
		(property "Reference" "C447"
			(at 0 0 180)
			(layer "F.SilkS")
			(hide yes)
			(effects
				(font
					(size 1.27 1.27)
				)
			)
		)
		(property "Value" "SC4D7U25V5KX-1-GP"
			(at -0.0762 -6.1214 180)
			(unlocked yes)
			(layer "F.Fab")
			(hide yes)
			(effects
				(font
					(size 1.016 1.016)
					(thickness 0.1524)
				)
			)
		)
		(property "Device Type" "C805H58"
			(at -0.0762 -8.1534 180)
			(unlocked yes)
			(layer "F.Fab")
			(hide yes)
			(effects
				(font
					(size 1.016 1.016)
					(thickness 0.1524)
				)
			)
		)
		(duplicate_pad_numbers_are_jumpers no)
		(fp_line
			(start 0.635 0)
			(end -0.635 0)
			(stroke
				(width 0.508)
				(type default)
			)
			(layer "F.SilkS")
		)
		(fp_rect
			(start -0.9652 1.778)
			(end 0.9652 -1.778)
			(stroke
				(width 0)
				(type default)
			)
			(fill no)
			(layer "F.CrtYd")
		)
		(fp_poly
			(pts
				(xy -0.9652 -1.778) (xy 0.9652 -1.778) (xy 0.9652 1.778) (xy -0.9652 1.778)
			)
			(stroke
				(width 0)
				(type default)
			)
			(fill no)
			(layer "F.Fab")
		)
		(pad "1" smd rect
			(at 0 -0.9652 180)
			(size 1.397 1.143)
			(layers "F.Cu" "F.Mask" "F.Paste")
			(net "P12V_HDD31")
		)
		(pad "2" smd rect
			(at 0 0.9652 180)
			(size 1.397 1.143)
			(layers "F.Cu" "F.Mask" "F.Paste")
			(net "GND")
		)
	)
	(footprint ""
		(layer "F.Cu")
		(at 64.013334 -273.660616 90)
		(property "Reference" "C52"
			(at 0 0 90)
			(layer "F.SilkS")
			(hide yes)
			(effects
				(font
					(size 1.27 1.27)
				)
			)
		)
		(property "Value" "SCD01U16V1KX-GP"
			(at -2.8321 -1.7399 90)
			(unlocked yes)
			(layer "F.Fab")
			(hide yes)
			(effects
				(font
					(size 1.016 1.016)
					(thickness 0.1524)
				)
			)
		)
		(property "Device Type" "C0201H13"
			(at -2.8321 -3.2639 90)
			(unlocked yes)
			(layer "F.Fab")
			(hide yes)
			(effects
				(font
					(size 1.016 1.016)
					(thickness 0.1524)
				)
			)
		)
		(duplicate_pad_numbers_are_jumpers no)
		(fp_rect
			(start -0.2794 0.6477)
			(end 0.2794 -0.6477)
			(stroke
				(width 0)
				(type default)
			)
			(fill no)
			(layer "F.CrtYd")
		)
		(fp_rect
			(start -0.2794 0.6477)
			(end 0.2794 -0.6477)
			(stroke
				(width 0)
				(type default)
			)
			(fill no)
			(layer "F.Fab")
		)
		(pad "1" smd custom
			(at 0 -0.2794 90)
			(size 0.0762 0.0762)
			(layers "F.Cu" "F.Mask" "F.Paste")
			(net "SAS_HDD_RX_P1")
			(options
				(clearance outline)
				(anchor circle)
			)
			(primitives
				(gr_poly
					(pts
						(arc
							(start 0.1524 -0.127)
							(mid 0.137521 -0.162921)
							(end 0.1016 -0.1778)
						)
						(arc
							(start -0.1016 -0.1778)
							(mid -0.137521 -0.162921)
							(end -0.1524 -0.127)
						)
						(arc
							(start -0.1524 0.127)
							(mid -0.137521 0.162921)
							(end -0.1016 0.1778)
						)
						(arc
							(start 0.1016 0.1778)
							(mid 0.137521 0.162921)
							(end 0.1524 0.127)
						)
					)
					(width 0)
					(fill yes)
				)
			)
		)
		(pad "2" smd custom
			(at 0 0.2794 90)
			(size 0.0762 0.0762)
			(layers "F.Cu" "F.Mask" "F.Paste")
			(net "PHY_SCC_A_TO_DRV_A_1_DP")
			(options
				(clearance outline)
				(anchor circle)
			)
			(primitives
				(gr_poly
					(pts
						(arc
							(start 0.1524 -0.127)
							(mid 0.137521 -0.162921)
							(end 0.1016 -0.1778)
						)
						(arc
							(start -0.1016 -0.1778)
							(mid -0.137521 -0.162921)
							(end -0.1524 -0.127)
						)
						(arc
							(start -0.1524 0.127)
							(mid -0.137521 0.162921)
							(end -0.1016 0.1778)
						)
						(arc
							(start 0.1016 0.1778)
							(mid 0.137521 0.162921)
							(end 0.1524 0.127)
						)
					)
					(width 0)
					(fill yes)
				)
			)
		)
	)
	(footprint ""
		(layer "F.Cu")
		(at 118.382796 -177.270918)
		(property "Reference" "R474"
			(at 0 0 0)
			(layer "F.SilkS")
			(hide yes)
			(effects
				(font
					(size 1.27 1.27)
				)
			)
		)
		(property "Value" "2R6F-GP"
			(at -0.0508 -4.8514 0)
			(unlocked yes)
			(layer "F.Fab")
			(hide yes)
			(effects
				(font
					(size 1.016 1.016)
					(thickness 0.1524)
				)
			)
		)
		(property "Device Type" "R1206H26"
			(at 0 -6.3754 0)
			(unlocked yes)
			(layer "F.Fab")
			(hide yes)
			(effects
				(font
					(size 1.016 1.016)
					(thickness 0.1524)
				)
			)
		)
		(duplicate_pad_numbers_are_jumpers no)
		(fp_line
			(start -1.016 -2.2352)
			(end 1.016 -2.2352)
			(stroke
				(width 0.1524)
				(type default)
			)
			(layer "F.SilkS")
		)
		(fp_line
			(start -1.016 2.2352)
			(end -1.016 -2.2352)
			(stroke
				(width 0.1524)
				(type default)
			)
			(layer "F.SilkS")
		)
		(fp_line
			(start 1.016 -2.2352)
			(end 1.016 2.2352)
			(stroke
				(width 0.1524)
				(type default)
			)
			(layer "F.SilkS")
		)
		(fp_line
			(start 1.016 2.2352)
			(end -1.016 2.2352)
			(stroke
				(width 0.1524)
				(type default)
			)
			(layer "F.SilkS")
		)
		(fp_rect
			(start -1.0922 2.3114)
			(end 1.0922 -2.3114)
			(stroke
				(width 0)
				(type default)
			)
			(fill no)
			(layer "F.CrtYd")
		)
		(fp_poly
			(pts
				(xy -1.0922 -2.3114) (xy 1.0922 -2.3114) (xy 1.0922 2.3114) (xy -1.0922 2.3114)
			)
			(stroke
				(width 0)
				(type default)
			)
			(fill no)
			(layer "F.Fab")
		)
		(pad "1" smd rect
			(at 0 -1.397)
			(size 1.651 1.27)
			(layers "F.Cu" "F.Mask" "F.Paste")
			(net "P5V_HDD15")
		)
		(pad "2" smd rect
			(at 0 1.397)
			(size 1.651 1.27)
			(layers "F.Cu" "F.Mask" "F.Paste")
			(net "5V_PRE_15")
		)
	)
	(footprint ""
		(layer "F.Cu")
		(at 458.3049 -160.252918 -90)
		(property "Reference" "Q133"
			(at 0 0 270)
			(layer "F.SilkS")
			(hide yes)
			(effects
				(font
					(size 1.27 1.27)
				)
			)
		)
		(property "Value" "2N7002KDW-GP"
			(at -2.3622 -8.2042 270)
			(unlocked yes)
			(layer "F.Fab")
			(hide yes)
			(effects
				(font
					(size 1.016 1.016)
					(thickness 0.1524)
				)
			)
		)
		(property "Device Type" "SOT-363H44"
			(at -2.3622 -10.1092 270)
			(unlocked yes)
			(layer "F.Fab")
			(hide yes)
			(effects
				(font
					(size 1.016 1.016)
					(thickness 0.1524)
				)
			)
		)
		(duplicate_pad_numbers_are_jumpers no)
		(fp_line
			(start -1.4478 1.7018)
			(end 1.4478 1.7018)
			(stroke
				(width 0.1524)
				(type default)
			)
			(layer "F.SilkS")
		)
		(fp_line
			(start 1.4478 1.7018)
			(end 1.4478 -1.7018)
			(stroke
				(width 0.1524)
				(type default)
			)
			(layer "F.SilkS")
		)
		(fp_line
			(start -1.27 1.524)
			(end -1.27 0.6604)
			(stroke
				(width 0.4826)
				(type default)
			)
			(layer "F.SilkS")
		)
		(fp_line
			(start -1.4478 -1.7018)
			(end -1.4478 1.7018)
			(stroke
				(width 0.1524)
				(type default)
			)
			(layer "F.SilkS")
		)
		(fp_line
			(start 1.4478 -1.7018)
			(end -1.4478 -1.7018)
			(stroke
				(width 0.1524)
				(type default)
			)
			(layer "F.SilkS")
		)
		(fp_poly
			(pts
				(xy -1.524 -1.778) (xy 1.524 -1.778) (xy 1.524 1.778) (xy -1.524 1.778)
			)
			(stroke
				(width 0)
				(type default)
			)
			(fill no)
			(layer "F.CrtYd")
		)
		(fp_poly
			(pts
				(xy -1.524 -1.778) (xy 1.524 -1.778) (xy 1.524 1.778) (xy -1.524 1.778)
			)
			(stroke
				(width 0)
				(type default)
			)
			(fill no)
			(layer "F.Fab")
		)
		(pad "1" smd rect
			(at -0.65024 0.9398 270)
			(size 0.4064 1.016)
			(layers "F.Cu" "F.Mask" "F.Paste")
			(net "GND")
		)
		(pad "2" smd rect
			(at 0 0.9398 270)
			(size 0.4064 1.016)
			(layers "F.Cu" "F.Mask" "F.Paste")
			(net "SW_PWR_R_HDD22")
		)
		(pad "3" smd rect
			(at 0.65024 0.9398 270)
			(size 0.4064 1.016)
			(layers "F.Cu" "F.Mask" "F.Paste")
			(net "SW_HDD_P22")
		)
		(pad "4" smd rect
			(at 0.65024 -0.9398 270)
			(size 0.4064 1.016)
			(layers "F.Cu" "F.Mask" "F.Paste")
			(net "GND")
		)
		(pad "5" smd rect
			(at 0 -0.9398 270)
			(size 0.4064 1.016)
			(layers "F.Cu" "F.Mask" "F.Paste")
			(net "SW_HDD_G22")
		)
		(pad "6" smd rect
			(at -0.65024 -0.9398 270)
			(size 0.4064 1.016)
			(layers "F.Cu" "F.Mask" "F.Paste")
			(net "SW_HDD_R22")
		)
	)
	(footprint ""
		(layer "F.Cu")
		(at 259.96773 21.69795 -90)
		(property "Reference" "C45"
			(at 0 0 270)
			(layer "F.SilkS")
			(hide yes)
			(effects
				(font
					(size 1.27 1.27)
				)
			)
		)
		(property "Value" "SC47U16V0MX-GP"
			(at -0.00254 -4.78536 270)
			(unlocked yes)
			(layer "F.Fab")
			(hide yes)
			(effects
				(font
					(size 1.016 1.016)
					(thickness 0.1524)
				)
			)
		)
		(property "Device Type" "C1210H107"
			(at -0.00254 -6.38048 270)
			(unlocked yes)
			(layer "F.Fab")
			(hide yes)
			(effects
				(font
					(size 1.016 1.016)
					(thickness 0.1524)
				)
			)
		)
		(duplicate_pad_numbers_are_jumpers no)
		(fp_line
			(start -1.5748 2.3368)
			(end 1.5748 2.3368)
			(stroke
				(width 0.1524)
				(type default)
			)
			(layer "F.SilkS")
		)
		(fp_line
			(start 1.5748 2.3368)
			(end 1.5748 0.762)
			(stroke
				(width 0.1524)
				(type default)
			)
			(layer "F.SilkS")
		)
		(fp_line
			(start -1.5748 0.762)
			(end -1.5748 2.3368)
			(stroke
				(width 0.1524)
				(type default)
			)
			(layer "F.SilkS")
		)
		(fp_line
			(start 1.5748 -0.762)
			(end 1.5748 -2.3368)
			(stroke
				(width 0.1524)
				(type default)
			)
			(layer "F.SilkS")
		)
		(fp_line
			(start -1.5748 -2.3368)
			(end -1.5748 -0.762)
			(stroke
				(width 0.1524)
				(type default)
			)
			(layer "F.SilkS")
		)
		(fp_line
			(start 1.5748 -2.3368)
			(end -1.5748 -2.3368)
			(stroke
				(width 0.1524)
				(type default)
			)
			(layer "F.SilkS")
		)
		(fp_rect
			(start -1.651 2.413)
			(end 1.651 -2.413)
			(stroke
				(width 0)
				(type default)
			)
			(fill no)
			(layer "F.CrtYd")
		)
		(fp_poly
			(pts
				(xy 1.651 2.413) (xy 1.651 -2.413) (xy -1.651 -2.413) (xy -1.651 2.413)
			)
			(stroke
				(width 0)
				(type default)
			)
			(fill no)
			(layer "F.Fab")
		)
		(pad "1" smd rect
			(at 0 -1.4732 270)
			(size 2.794 1.397)
			(layers "F.Cu" "F.Mask" "F.Paste")
			(net "P5V_USB_A")
		)
		(pad "2" smd rect
			(at 0 1.4732 270)
			(size 2.794 1.397)
			(layers "F.Cu" "F.Mask" "F.Paste")
			(net "GND")
		)
	)
	(footprint ""
		(layer "F.Cu")
		(at 463.674968 -9.19988)
		(property "Reference" ""
			(at 0 0 0)
			(layer "F.SilkS")
			(hide yes)
			(effects
				(font
					(size 1.27 1.27)
				)
			)
		)
		(property "Value" "*"
			(at -6.1214 1.4351 0)
			(unlocked yes)
			(layer "F.Fab")
			(hide yes)
			(effects
				(font
					(size 1.016 1.016)
					(thickness 0.1524)
				)
			)
		)
		(duplicate_pad_numbers_are_jumpers no)
		(fp_poly
			(pts
				(arc
					(start 5.0673 0)
					(mid -5.0673 0)
					(end 5.0673 0)
				)
			)
			(stroke
				(width 0)
				(type default)
			)
			(fill no)
			(layer "B.CrtYd")
		)
		(fp_poly
			(pts
				(arc
					(start 5.0673 0)
					(mid -5.0673 0)
					(end 5.0673 0)
				)
			)
			(stroke
				(width 0)
				(type default)
			)
			(fill no)
			(layer "F.CrtYd")
		)
		(fp_poly
			(pts
				(arc
					(start 5.0673 0)
					(mid -5.0673 0)
					(end 5.0673 0)
				)
			)
			(stroke
				(width 0)
				(type default)
			)
			(fill no)
			(layer "B.Fab")
		)
		(fp_poly
			(pts
				(arc
					(start 5.0673 0)
					(mid -5.0673 0)
					(end 5.0673 0)
				)
			)
			(stroke
				(width 0)
				(type default)
			)
			(fill no)
			(layer "F.Fab")
		)
		(pad "1" thru_hole circle
			(at 0 0)
			(size 9.525 9.525)
			(drill 5.715)
			(layers "*.Cu" "*.Mask")
			(remove_unused_layers no)
			(net "Net_109")
			(clearance -1.397)
			(thermal_gap 0.3048)
			(padstack
				(mode front_inner_back)
				(layer "Inner"
					(shape circle)
					(size 6.1214 6.1214)
					(clearance 0.3048)
				)
				(layer "B.Cu"
					(shape circle)
					(size 9.525 9.525)
					(clearance -1.397)
				)
			)
		)
		(zone
			(layers "F.Cu" "B.Cu" "In1.Cu" "In2.Cu" "In3.Cu" "In4.Cu" "In5.Cu" "In6.Cu"
				"In7.Cu" "In8.Cu" "In9.Cu" "In10.Cu"
			)
			(hatch none 0.5)
			(connect_pads
				(clearance 0)
			)
			(min_thickness 0.25)
			(keepout
				(tracks not_allowed)
				(vias allowed)
				(pads allowed)
				(copperpour not_allowed)
				(footprints allowed)
			)
			(placement
				(enabled no)
				(sheetname "")
			)
			(fill
				(thermal_gap 0.5)
				(thermal_bridge_width 0.5)
				(island_removal_mode 0)
			)
			(polygon
				(pts
					(arc
						(start 468.437468 -9.19988)
						(mid 458.912468 -9.19988)
						(end 468.437468 -9.19988)
					)
				)
			)
		)
	)
	(footprint ""
		(layer "F.Cu")
		(at 282.3464 -280.2636)
		(property "Reference" "C38"
			(at 0 0 0)
			(layer "F.SilkS")
			(hide yes)
			(effects
				(font
					(size 1.27 1.27)
				)
			)
		)
		(property "Value" "SCD1U16V2KX-3GP"
			(at 1.1811 -2.7051 0)
			(unlocked yes)
			(layer "F.Fab")
			(hide yes)
			(effects
				(font
					(size 1.016 1.016)
					(thickness 0.1524)
				)
			)
		)
		(property "Device Type" "C402H22"
			(at 1.1811 -4.2291 0)
			(unlocked yes)
			(layer "F.Fab")
			(hide yes)
			(effects
				(font
					(size 1.016 1.016)
					(thickness 0.1524)
				)
			)
		)
		(duplicate_pad_numbers_are_jumpers no)
		(fp_rect
			(start -0.4318 0.9525)
			(end 0.4318 -0.9525)
			(stroke
				(width 0)
				(type default)
			)
			(fill no)
			(layer "F.CrtYd")
		)
		(fp_rect
			(start -0.4318 0.9525)
			(end 0.4318 -0.9525)
			(stroke
				(width 0)
				(type default)
			)
			(fill no)
			(layer "F.Fab")
		)
		(pad "1" smd custom
			(at 0 -0.4445)
			(size 0.1524 0.1524)
			(layers "F.Cu" "F.Mask" "F.Paste")
			(net "P3V3_STBY_A")
			(options
				(clearance outline)
				(anchor circle)
			)
			(primitives
				(gr_poly
					(pts
						(arc
							(start 0.3048 -0.2032)
							(mid 0.275042 -0.275042)
							(end 0.2032 -0.3048)
						)
						(arc
							(start -0.2032 -0.3048)
							(mid -0.275042 -0.275042)
							(end -0.3048 -0.2032)
						)
						(arc
							(start -0.3048 0.2032)
							(mid -0.275042 0.275042)
							(end -0.2032 0.3048)
						)
						(arc
							(start 0.2032 0.3048)
							(mid 0.275042 0.275042)
							(end 0.3048 0.2032)
						)
					)
					(width 0)
					(fill yes)
				)
			)
		)
		(pad "2" smd custom
			(at 0 0.4445)
			(size 0.1524 0.1524)
			(layers "F.Cu" "F.Mask" "F.Paste")
			(net "GND")
			(options
				(clearance outline)
				(anchor circle)
			)
			(primitives
				(gr_poly
					(pts
						(arc
							(start 0.3048 -0.2032)
							(mid 0.275042 -0.275042)
							(end 0.2032 -0.3048)
						)
						(arc
							(start -0.2032 -0.3048)
							(mid -0.275042 -0.275042)
							(end -0.3048 -0.2032)
						)
						(arc
							(start -0.3048 0.2032)
							(mid -0.275042 0.275042)
							(end -0.2032 0.3048)
						)
						(arc
							(start 0.2032 0.3048)
							(mid 0.275042 0.275042)
							(end 0.3048 0.2032)
						)
					)
					(width 0)
					(fill yes)
				)
			)
		)
	)
)
